(kicad_pcb
	(version 20260206)
	(generator "pcbnew")
	(generator_version "10.0")
	(general
		(thickness 1.6)
		(legacy_teardrops no)
	)
	(paper "A4")
	(title_block
		(title "panther-plus-userver — 13130-1b_20150205.brd")
		(comment 1 "Honey Badger (Wiwynn) / footprint 624 of 1509 (DIMM4), pads 205-210 of 210")
	)
	(layers
		(0 "F.Cu" signal "TOP")
		(4 "In1.Cu" signal "L2")
		(6 "In2.Cu" signal "L3")
		(8 "In3.Cu" signal "L4")
		(10 "In4.Cu" signal "L5")
		(12 "In5.Cu" signal "L6")
		(14 "In6.Cu" signal "L7")
		(16 "In7.Cu" signal "L8")
		(18 "In8.Cu" signal "L9")
		(20 "In9.Cu" signal "L10")
		(22 "In10.Cu" signal "L11")
		(2 "B.Cu" signal "BOTTOM")
		(9 "F.Adhes" user "F.Adhesive")
		(11 "B.Adhes" user "B.Adhesive")
		(13 "F.Paste" user "Package Geometry/Pastemask Top")
		(15 "B.Paste" user "Package Geometry/Pastemask Bottom")
		(5 "F.SilkS" user "Ref Des/Silkscreen Top")
		(7 "B.SilkS" user "Ref Des/Silkscreen Bottom")
		(1 "F.Mask" user "Board Geometry/Soldermask Top")
		(3 "B.Mask" user "Board Geometry/Soldermask Bottom")
		(17 "Dwgs.User" user "User.Drawings")
		(19 "Cmts.User" user "User.Comments")
		(21 "Eco1.User" user "User.Eco1")
		(23 "Eco2.User" user "User.Eco2")
		(25 "Edge.Cuts" user "Board Geometry/Outline")
		(27 "Margin" user)
		(31 "F.CrtYd" user "Package Geometry/Place Bound Top")
		(29 "B.CrtYd" user "Package Geometry/Place Bound Bottom")
		(35 "F.Fab" user "Ref Des/Assembly Top")
		(33 "B.Fab" user "Ref Des/Assembly Bottom")
	)
	(footprint ""
		(layer "F.Cu")
		(at 159.999934 -5.790692)
		(property "Reference" "DIMM4"
			(at 0 0 0)
			(layer "F.SilkS")
			(hide yes)
			(effects
				(font
					(size 1.27 1.27)
				)
			)
		)
		(property "Value" "DDR3-204P-174-COLAY-1-GP"
			(at -40.682164 -17.468088 0)
			(unlocked yes)
			(layer "F.Fab")
			(hide yes)
			(effects
				(font
					(size 1.016 1.016)
					(thickness 0.1524)
				)
			)
		)
		(property "Device Type" "AS0A626-H8SN-7H-COLAY-1"
			(at -40.682164 -18.992088 0)
			(unlocked yes)
			(layer "F.Fab")
			(hide yes)
			(effects
				(font
					(size 1.016 1.016)
					(thickness 0.1524)
				)
			)
		)
		(duplicate_pad_numbers_are_jumpers no)
		(pad "203" smd custom
			(at 31.34995 4.106672)
			(size 0.1143 0.1143)
			(layers "F.Cu" "F.Mask" "F.Paste")
			(net "PV_VTT_DDR_B")
			(options
				(clearance outline)
				(anchor circle)
			)
			(primitives
				(gr_poly
					(pts
						(xy 0 0.9017) (xy -0.03175 0.89916) (xy -0.0635 0.889) (xy -0.09144 0.87376) (xy -0.11684 0.85344)
						(xy -0.13716 0.82804) (xy -0.1524 0.8001) (xy -0.16256 0.76835) (xy -0.1651 0.7366) (xy -0.1651 0.11938)
						(xy -0.17272 0.11176) (xy -0.19812 0.0762) (xy -0.2032 0.06604) (xy -0.20701 0.05715) (xy -0.21209 0.04699)
						(xy -0.2159 0.03683) (xy -0.21844 0.02667) (xy -0.22225 0.01524) (xy -0.22352 0.00508) (xy -0.22606 -0.00508)
						(xy -0.22733 -0.01651) (xy -0.22733 -0.02667) (xy -0.2286 -0.0381) (xy -0.22733 -0.04953) (xy -0.22733 -0.05969)
						(xy -0.22606 -0.07112) (xy -0.22352 -0.08128) (xy -0.22225 -0.09144) (xy -0.21844 -0.10287) (xy -0.2159 -0.11303)
						(xy -0.21209 -0.12319) (xy -0.20701 -0.13335) (xy -0.2032 -0.14224) (xy -0.19812 -0.1524) (xy -0.17272 -0.18796)
						(xy -0.1651 -0.19558) (xy -0.1651 -0.7366) (xy -0.16256 -0.76835) (xy -0.1524 -0.8001) (xy -0.13716 -0.82804)
						(xy -0.11684 -0.85344) (xy -0.09144 -0.87376) (xy -0.0635 -0.889) (xy -0.03175 -0.89916) (xy 0 -0.9017)
						(xy 0.03175 -0.89916) (xy 0.0635 -0.889) (xy 0.09144 -0.87376) (xy 0.11684 -0.85344) (xy 0.13716 -0.82804)
						(xy 0.1524 -0.8001) (xy 0.16256 -0.76835) (xy 0.1651 -0.7366) (xy 0.1651 -0.19685) (xy 0.17272 -0.18923)
						(xy 0.17907 -0.18034) (xy 0.18669 -0.17145) (xy 0.19177 -0.16256) (xy 0.19812 -0.15367) (xy 0.20828 -0.13335)
						(xy 0.21971 -0.10287) (xy 0.22225 -0.09271) (xy 0.22479 -0.08128) (xy 0.22606 -0.07112) (xy 0.2286 -0.05969)
						(xy 0.2286 -0.01651) (xy 0.22606 -0.00508) (xy 0.22479 0.00508) (xy 0.22225 0.01651) (xy 0.21971 0.02667)
						(xy 0.20828 0.05715) (xy 0.19812 0.07747) (xy 0.19177 0.08636) (xy 0.18669 0.09525) (xy 0.17907 0.10414)
						(xy 0.17272 0.11303) (xy 0.1651 0.12065) (xy 0.1651 0.7366) (xy 0.16256 0.76835) (xy 0.1524 0.8001)
						(xy 0.13716 0.82804) (xy 0.11684 0.85344) (xy 0.09144 0.87376) (xy 0.0635 0.889) (xy 0.03175 0.89916)
					)
					(width 0)
					(fill yes)
				)
			)
		)
		(pad "204" smd custom
			(at 31.649924 -4.106672)
			(size 0.1143 0.1143)
			(layers "F.Cu" "F.Mask" "F.Paste")
			(net "PV_VTT_DDR_B")
			(options
				(clearance outline)
				(anchor circle)
			)
			(primitives
				(gr_poly
					(pts
						(xy 0 0.9017) (xy -0.03175 0.89916) (xy -0.0635 0.889) (xy -0.09144 0.87376) (xy -0.11684 0.85344)
						(xy -0.13716 0.82804) (xy -0.1524 0.8001) (xy -0.16256 0.76835) (xy -0.1651 0.7366) (xy -0.1651 0.19685)
						(xy -0.17272 0.18923) (xy -0.17907 0.18034) (xy -0.18669 0.17145) (xy -0.19177 0.16256) (xy -0.19812 0.15367)
						(xy -0.20828 0.13335) (xy -0.21971 0.10287) (xy -0.22225 0.09271) (xy -0.22479 0.08128) (xy -0.22606 0.07112)
						(xy -0.2286 0.05969) (xy -0.2286 0.01651) (xy -0.22606 0.00508) (xy -0.22479 -0.00508) (xy -0.22225 -0.01651)
						(xy -0.21971 -0.02667) (xy -0.20828 -0.05715) (xy -0.19812 -0.07747) (xy -0.19177 -0.08636) (xy -0.18669 -0.09525)
						(xy -0.17907 -0.10414) (xy -0.17272 -0.11303) (xy -0.1651 -0.12065) (xy -0.1651 -0.7366) (xy -0.16256 -0.76835)
						(xy -0.1524 -0.8001) (xy -0.13716 -0.82804) (xy -0.11684 -0.85344) (xy -0.09144 -0.87376) (xy -0.0635 -0.889)
						(xy -0.03175 -0.89916) (xy 0 -0.9017) (xy 0.03175 -0.89916) (xy 0.0635 -0.889) (xy 0.09144 -0.87376)
						(xy 0.11684 -0.85344) (xy 0.13716 -0.82804) (xy 0.1524 -0.8001) (xy 0.16256 -0.76835) (xy 0.1651 -0.7366)
						(xy 0.1651 -0.11938) (xy 0.17272 -0.11176) (xy 0.19812 -0.0762) (xy 0.2032 -0.06604) (xy 0.20701 -0.05715)
						(xy 0.21209 -0.04699) (xy 0.2159 -0.03683) (xy 0.21844 -0.02667) (xy 0.22225 -0.01524) (xy 0.22352 -0.00508)
						(xy 0.22606 0.00508) (xy 0.22733 0.01651) (xy 0.22733 0.02667) (xy 0.2286 0.0381) (xy 0.22733 0.04953)
						(xy 0.22733 0.05969) (xy 0.22606 0.07112) (xy 0.22352 0.08128) (xy 0.22225 0.09144) (xy 0.21844 0.10287)
						(xy 0.2159 0.11303) (xy 0.21209 0.12319) (xy 0.20701 0.13335) (xy 0.2032 0.14224) (xy 0.19812 0.1524)
						(xy 0.17272 0.18796) (xy 0.1651 0.19558) (xy 0.1651 0.7366) (xy 0.16256 0.76835) (xy 0.1524 0.8001)
						(xy 0.13716 0.82804) (xy 0.11684 0.85344) (xy 0.09144 0.87376) (xy 0.0635 0.889) (xy 0.03175 0.89916)
					)
					(width 0)
					(fill yes)
				)
			)
		)
		(pad "205" smd rect
			(at -37.349938 -11.299952)
			(size 4.699 6.8072)
			(layers "F.Cu" "F.Mask" "F.Paste")
			(net "GND")
		)
		(pad "206" smd rect
			(at 37.349938 -11.299952)
			(size 4.699 6.8072)
			(layers "F.Cu" "F.Mask" "F.Paste")
			(net "GND")
		)
		(pad "207" smd rect
			(at -32.800036 -11.999976)
			(size 3.5052 4.5974)
			(layers "F.Cu" "F.Mask" "F.Paste")
			(net "GND")
		)
		(pad "208" smd rect
			(at 32.800036 -11.999976)
			(size 3.5052 4.5974)
			(layers "F.Cu" "F.Mask" "F.Paste")
			(net "GND")
		)
	)
)
